# T6G (Grand Teton) — schematic netlist excerpt (pin names and nets, part order shuffled) for the footprints in the layout excerpt that follows; sources: Cadence DE-HDL packaged netlist, KiCad conversion of 04192023_DAF0TMB3IC0_F0TG_MB_C_brd_V02_OCP.brd

C2243  Q_CAP  22UF 4V 20% X6S  pkg C0402  page 69 : A = PVDDCR_CPU1_P0 ; B = GND
C2464  Q_CAP  22UF 4V 20% X6S  pkg C0402  page 74 : A = PVDDCR_SOC_P1 ; B = GND
C598  Q_CAP  1UF 4V 20% X6S  pkg 0201  page 290 : A = P1V8_CPU0_RT1_1A_1D ; B = GND

(kicad_pcb
	(version 20260206)
	(generator "pcbnew")
	(generator_version "10.0")
	(general
		(thickness 1.6)
		(legacy_teardrops no)
	)
	(paper "A4")
	(title_block
		(title "04192023_DAF0TMB3IC0_F0TG_MB_C_brd_V02_OCP.brd")
		(comment 1 "Grand Teton / footprints 6609-6611 of 8354")
	)
	(layers
		(0 "F.Cu" signal "TOP")
		(4 "In1.Cu" signal "GND")
		(6 "In2.Cu" signal "IN1")
		(8 "In3.Cu" signal "GND1")
		(10 "In4.Cu" signal "IN2")
		(12 "In5.Cu" signal "GND2")
		(14 "In6.Cu" signal "IN3")
		(16 "In7.Cu" signal "GND3")
		(18 "In8.Cu" signal "VCC")
		(20 "In9.Cu" signal "VCC1")
		(22 "In10.Cu" signal "GND4")
		(24 "In11.Cu" signal "IN4")
		(26 "In12.Cu" signal "GND5")
		(28 "In13.Cu" signal "IN5")
		(30 "In14.Cu" signal "GND6")
		(32 "In15.Cu" signal "IN6")
		(34 "In16.Cu" signal "GND7")
		(2 "B.Cu" signal "BOTTOM")
		(9 "F.Adhes" user "F.Adhesive")
		(11 "B.Adhes" user "B.Adhesive")
		(13 "F.Paste" user "Package Geometry/Pastemask Top")
		(15 "B.Paste" user "Package Geometry/Pastemask Bottom")
		(5 "F.SilkS" user "Ref Des/Silkscreen Top")
		(7 "B.SilkS" user "Ref Des/Silkscreen Bottom")
		(1 "F.Mask" user "Board Geometry/Soldermask Top")
		(3 "B.Mask" user "Board Geometry/Soldermask Bottom")
		(17 "Dwgs.User" user "User.Drawings")
		(19 "Cmts.User" user "User.Comments")
		(21 "Eco1.User" user "User.Eco1")
		(23 "Eco2.User" user "User.Eco2")
		(25 "Edge.Cuts" user "Board Geometry/Outline")
		(27 "Margin" user)
		(31 "F.CrtYd" user "Package Geometry/Place Bound Top")
		(29 "B.CrtYd" user "Package Geometry/Place Bound Bottom")
		(35 "F.Fab" user "Ref Des/Assembly Top")
		(33 "B.Fab" user "Ref Des/Assembly Bottom")
	)
	(footprint ""
		(layer "B.Cu")
		(at 346.705936 -395.148562 90)
		(property "Reference" "C598"
			(at 0 0 90)
			(layer "B.SilkS")
			(hide yes)
			(effects
				(font
					(size 1.27 1.27)
				)
				(justify mirror)
			)
		)
		(property "Value" ""
			(at 0 0 90)
			(layer "B.Fab")
			(effects
				(font
					(size 1.27 1.27)
				)
				(justify mirror)
			)
		)
		(duplicate_pad_numbers_are_jumpers no)
		(fp_line
			(start 0.299974 -0.150114)
			(end -0.299974 -0.150114)
			(stroke
				(width 0.1)
				(type default)
			)
			(layer "B.Fab")
		)
		(fp_line
			(start -0.299974 -0.150114)
			(end -0.299974 0.150114)
			(stroke
				(width 0.1)
				(type default)
			)
			(layer "B.Fab")
		)
		(fp_line
			(start 0.299974 0.150114)
			(end 0.299974 -0.150114)
			(stroke
				(width 0.1)
				(type default)
			)
			(layer "B.Fab")
		)
		(fp_line
			(start -0.299974 0.150114)
			(end 0.299974 0.150114)
			(stroke
				(width 0.1)
				(type default)
			)
			(layer "B.Fab")
		)
		(pad "1" smd rect
			(at 0.2667 0 270)
			(size 0.3048 0.381)
			(layers "B.Cu" "B.Mask" "B.Paste")
			(net "P1V8_CPU0_RT1_1A_1D")
		)
		(pad "2" smd rect
			(at -0.2667 0 270)
			(size 0.3048 0.381)
			(layers "B.Cu" "B.Mask" "B.Paste")
			(net "GND")
		)
	)
	(footprint ""
		(layer "B.Cu")
		(at 117.895624 -257.455416)
		(property "Reference" "C2464"
			(at 0 0 0)
			(layer "B.SilkS")
			(hide yes)
			(effects
				(font
					(size 1.27 1.27)
				)
				(justify mirror)
			)
		)
		(property "Value" ""
			(at 0 0 0)
			(layer "B.Fab")
			(effects
				(font
					(size 1.27 1.27)
				)
				(justify mirror)
			)
		)
		(duplicate_pad_numbers_are_jumpers no)
		(fp_line
			(start -0.7874 -0.4064)
			(end -0.7874 0.4064)
			(stroke
				(width 0.1524)
				(type default)
			)
			(layer "B.SilkS")
		)
		(fp_line
			(start -0.7874 0.4064)
			(end 0.7874 0.4064)
			(stroke
				(width 0.1524)
				(type default)
			)
			(layer "B.SilkS")
		)
		(fp_line
			(start 0.7874 -0.4064)
			(end -0.7874 -0.4064)
			(stroke
				(width 0.1524)
				(type default)
			)
			(layer "B.SilkS")
		)
		(fp_line
			(start 0.7874 0.4064)
			(end 0.7874 -0.4064)
			(stroke
				(width 0.1524)
				(type default)
			)
			(layer "B.SilkS")
		)
		(fp_line
			(start -0.67945 -0.3048)
			(end -0.67945 0.3048)
			(stroke
				(width 0.1)
				(type default)
			)
			(layer "B.Fab")
		)
		(fp_line
			(start -0.67945 0.3048)
			(end -0.120396 0.3048)
			(stroke
				(width 0.1)
				(type default)
			)
			(layer "B.Fab")
		)
		(fp_line
			(start -0.12065 -0.3048)
			(end -0.67945 -0.3048)
			(stroke
				(width 0.1)
				(type default)
			)
			(layer "B.Fab")
		)
		(fp_line
			(start -0.12065 -0.2794)
			(end -0.12065 -0.3048)
			(stroke
				(width 0.1)
				(type default)
			)
			(layer "B.Fab")
		)
		(fp_line
			(start -0.120396 0.2794)
			(end 0.12065 0.2794)
			(stroke
				(width 0.1)
				(type default)
			)
			(layer "B.Fab")
		)
		(fp_line
			(start -0.120396 0.3048)
			(end -0.120396 0.2794)
			(stroke
				(width 0.1)
				(type default)
			)
			(layer "B.Fab")
		)
		(fp_line
			(start 0.12065 -0.305054)
			(end 0.12065 -0.2794)
			(stroke
				(width 0.1)
				(type default)
			)
			(layer "B.Fab")
		)
		(fp_line
			(start 0.12065 -0.2794)
			(end -0.12065 -0.2794)
			(stroke
				(width 0.1)
				(type default)
			)
			(layer "B.Fab")
		)
		(fp_line
			(start 0.12065 0.2794)
			(end 0.12065 0.3048)
			(stroke
				(width 0.1)
				(type default)
			)
			(layer "B.Fab")
		)
		(fp_line
			(start 0.12065 0.3048)
			(end 0.67945 0.3048)
			(stroke
				(width 0.1)
				(type default)
			)
			(layer "B.Fab")
		)
		(fp_line
			(start 0.67945 -0.305054)
			(end 0.12065 -0.305054)
			(stroke
				(width 0.1)
				(type default)
			)
			(layer "B.Fab")
		)
		(fp_line
			(start 0.67945 0.3048)
			(end 0.67945 -0.305054)
			(stroke
				(width 0.1)
				(type default)
			)
			(layer "B.Fab")
		)
		(pad "1" smd circle
			(at 0.40005 0 180)
			(size 0 0)
			(layers "B.Cu" "B.Mask" "B.Paste")
			(net "PVDDCR_SOC_P1")
		)
		(pad "2" smd circle
			(at -0.40005 0 180)
			(size 0 0)
			(layers "B.Cu" "B.Mask" "B.Paste")
			(net "GND")
		)
	)
	(footprint ""
		(layer "B.Cu")
		(at 369.392454 -267.498576)
		(property "Reference" "C2243"
			(at 0 0 0)
			(layer "B.SilkS")
			(hide yes)
			(effects
				(font
					(size 1.27 1.27)
				)
				(justify mirror)
			)
		)
		(property "Value" ""
			(at 0 0 0)
			(layer "B.Fab")
			(effects
				(font
					(size 1.27 1.27)
				)
				(justify mirror)
			)
		)
		(duplicate_pad_numbers_are_jumpers no)
		(fp_line
			(start -0.7874 -0.4064)
			(end -0.7874 0.4064)
			(stroke
				(width 0.1524)
				(type default)
			)
			(layer "B.SilkS")
		)
		(fp_line
			(start -0.7874 0.4064)
			(end 0.7874 0.4064)
			(stroke
				(width 0.1524)
				(type default)
			)
			(layer "B.SilkS")
		)
		(fp_line
			(start 0.7874 -0.4064)
			(end -0.7874 -0.4064)
			(stroke
				(width 0.1524)
				(type default)
			)
			(layer "B.SilkS")
		)
		(fp_line
			(start 0.7874 0.4064)
			(end 0.7874 -0.4064)
			(stroke
				(width 0.1524)
				(type default)
			)
			(layer "B.SilkS")
		)
		(fp_line
			(start -0.67945 -0.3048)
			(end -0.67945 0.3048)
			(stroke
				(width 0.1)
				(type default)
			)
			(layer "B.Fab")
		)
		(fp_line
			(start -0.67945 0.3048)
			(end -0.120396 0.3048)
			(stroke
				(width 0.1)
				(type default)
			)
			(layer "B.Fab")
		)
		(fp_line
			(start -0.12065 -0.3048)
			(end -0.67945 -0.3048)
			(stroke
				(width 0.1)
				(type default)
			)
			(layer "B.Fab")
		)
		(fp_line
			(start -0.12065 -0.2794)
			(end -0.12065 -0.3048)
			(stroke
				(width 0.1)
				(type default)
			)
			(layer "B.Fab")
		)
		(fp_line
			(start -0.120396 0.2794)
			(end 0.12065 0.2794)
			(stroke
				(width 0.1)
				(type default)
			)
			(layer "B.Fab")
		)
		(fp_line
			(start -0.120396 0.3048)
			(end -0.120396 0.2794)
			(stroke
				(width 0.1)
				(type default)
			)
			(layer "B.Fab")
		)
		(fp_line
			(start 0.12065 -0.305054)
			(end 0.12065 -0.2794)
			(stroke
				(width 0.1)
				(type default)
			)
			(layer "B.Fab")
		)
		(fp_line
			(start 0.12065 -0.2794)
			(end -0.12065 -0.2794)
			(stroke
				(width 0.1)
				(type default)
			)
			(layer "B.Fab")
		)
		(fp_line
			(start 0.12065 0.2794)
			(end 0.12065 0.3048)
			(stroke
				(width 0.1)
				(type default)
			)
			(layer "B.Fab")
		)
		(fp_line
			(start 0.12065 0.3048)
			(end 0.67945 0.3048)
			(stroke
				(width 0.1)
				(type default)
			)
			(layer "B.Fab")
		)
		(fp_line
			(start 0.67945 -0.305054)
			(end 0.12065 -0.305054)
			(stroke
				(width 0.1)
				(type default)
			)
			(layer "B.Fab")
		)
		(fp_line
			(start 0.67945 0.3048)
			(end 0.67945 -0.305054)
			(stroke
				(width 0.1)
				(type default)
			)
			(layer "B.Fab")
		)
		(pad "1" smd circle
			(at 0.40005 0 180)
			(size 0 0)
			(layers "B.Cu" "B.Mask" "B.Paste")
			(net "PVDDCR_CPU1_P0")
		)
		(pad "2" smd circle
			(at -0.40005 0 180)
			(size 0 0)
			(layers "B.Cu" "B.Mask" "B.Paste")
			(net "GND")
		)
	)
)
